# T6G (Grand Teton) — schematic netlist excerpt (pin names and nets, part order shuffled) for the footprints in the layout excerpt that follows; sources: Cadence DE-HDL packaged netlist, KiCad conversion of 04192023_DAF0TMB3IC0_F0TG_MB_C_brd_V02_OCP.brd

X8008  TP_TDR_4P_FTS  TP_TDR_4P_DIP EMPTY  pkg TH  page 260
  S1  = TDR_DIFF_85_IN1_DN
  P1  = T1_GND
  P2  = T1_GND
  S2  = TDR_DIFF_85_IN1_DP

R616  Q_RES  0 5% CHIP  pkg 0201LF  page 309 : A = CLK_100M_RETIMER_CPU0_P3_R_DN ; B = CLK_100M_RETIMER_CPU0_P3_DN
R1044  Q_RES  1K 1% CHIP  pkg 0201LF  page 289 : A = U15_E2 ; B = GND

(kicad_pcb
	(version 20260206)
	(generator "pcbnew")
	(generator_version "10.0")
	(general
		(thickness 1.6)
		(legacy_teardrops no)
	)
	(paper "A4")
	(title_block
		(title "04192023_DAF0TMB3IC0_F0TG_MB_C_brd_V02_OCP.brd")
		(comment 1 "Grand Teton / footprints 1212-1214 of 8354")
	)
	(layers
		(0 "F.Cu" signal "TOP")
		(4 "In1.Cu" signal "GND")
		(6 "In2.Cu" signal "IN1")
		(8 "In3.Cu" signal "GND1")
		(10 "In4.Cu" signal "IN2")
		(12 "In5.Cu" signal "GND2")
		(14 "In6.Cu" signal "IN3")
		(16 "In7.Cu" signal "GND3")
		(18 "In8.Cu" signal "VCC")
		(20 "In9.Cu" signal "VCC1")
		(22 "In10.Cu" signal "GND4")
		(24 "In11.Cu" signal "IN4")
		(26 "In12.Cu" signal "GND5")
		(28 "In13.Cu" signal "IN5")
		(30 "In14.Cu" signal "GND6")
		(32 "In15.Cu" signal "IN6")
		(34 "In16.Cu" signal "GND7")
		(2 "B.Cu" signal "BOTTOM")
		(9 "F.Adhes" user "F.Adhesive")
		(11 "B.Adhes" user "B.Adhesive")
		(13 "F.Paste" user "Package Geometry/Pastemask Top")
		(15 "B.Paste" user "Package Geometry/Pastemask Bottom")
		(5 "F.SilkS" user "Ref Des/Silkscreen Top")
		(7 "B.SilkS" user "Ref Des/Silkscreen Bottom")
		(1 "F.Mask" user "Board Geometry/Soldermask Top")
		(3 "B.Mask" user "Board Geometry/Soldermask Bottom")
		(17 "Dwgs.User" user "User.Drawings")
		(19 "Cmts.User" user "User.Comments")
		(21 "Eco1.User" user "User.Eco1")
		(23 "Eco2.User" user "User.Eco2")
		(25 "Edge.Cuts" user "Board Geometry/Outline")
		(27 "Margin" user)
		(31 "F.CrtYd" user "Package Geometry/Place Bound Top")
		(29 "B.CrtYd" user "Package Geometry/Place Bound Bottom")
		(35 "F.Fab" user "Ref Des/Assembly Top")
		(33 "B.Fab" user "Ref Des/Assembly Bottom")
	)
	(footprint ""
		(layer "F.Cu")
		(at 509.384808 -142.846806 90)
		(property "Reference" "X8008"
			(at -2.000758 1.744472 0)
			(unlocked yes)
			(layer "F.SilkS")
			(effects
				(font
					(size 0.7874 0.5842)
					(thickness 0.1524)
				)
				(justify left)
			)
		)
		(property "Value" ""
			(at 0 0 90)
			(layer "F.Fab")
			(effects
				(font
					(size 1.27 1.27)
				)
			)
		)
		(property "Device Type" "TP_TDR_4P_FTS_TH-TP_TDR_4P_DIP,EMPTY,TP15"
			(at 1.30175 1.27 180)
			(unlocked yes)
			(layer "F.Fab")
			(hide yes)
			(effects
				(font
					(size 0.635 0.4064)
					(thickness 0.1524)
				)
			)
		)
		(property "User Part Number" "N_A"
			(at 1.30175 1.27 180)
			(unlocked yes)
			(layer "Cmts.User")
			(hide yes)
			(effects
				(font
					(size 0.635 0.4064)
					(thickness 0.1524)
				)
			)
		)
		(duplicate_pad_numbers_are_jumpers no)
		(fp_line
			(start 2.54 -1.27)
			(end 0 -1.27)
			(stroke
				(width 0.1524)
				(type default)
			)
			(layer "F.SilkS")
		)
		(fp_line
			(start 0 -1.27)
			(end 0 -0.635)
			(stroke
				(width 0.1524)
				(type default)
			)
			(layer "F.SilkS")
		)
		(fp_line
			(start 2.54 -1.1303)
			(end 2.54 -1.27)
			(stroke
				(width 0.1524)
				(type default)
			)
			(layer "F.SilkS")
		)
		(fp_line
			(start 0 0.635)
			(end 0 1.905)
			(stroke
				(width 0.1524)
				(type default)
			)
			(layer "F.SilkS")
		)
		(fp_line
			(start 2.54 1.4097)
			(end 2.54 1.1303)
			(stroke
				(width 0.1524)
				(type default)
			)
			(layer "F.SilkS")
		)
		(fp_line
			(start 0 3.175)
			(end 0 3.81)
			(stroke
				(width 0.1524)
				(type default)
			)
			(layer "F.SilkS")
		)
		(fp_line
			(start 2.54 3.81)
			(end 2.54 3.6703)
			(stroke
				(width 0.1524)
				(type default)
			)
			(layer "F.SilkS")
		)
		(fp_line
			(start 0 3.81)
			(end 2.54 3.81)
			(stroke
				(width 0.1524)
				(type default)
			)
			(layer "F.SilkS")
		)
		(fp_poly
			(pts
				(xy -2.285746 -0.762) (xy -0.761746 0) (xy -2.285746 0.762)
			)
			(stroke
				(width 0)
				(type default)
			)
			(fill yes)
			(layer "F.SilkS")
		)
		(fp_line
			(start 2.54 -1.27)
			(end 0 -1.27)
			(stroke
				(width 0.1)
				(type default)
			)
			(layer "F.Fab")
		)
		(fp_line
			(start 0 -1.27)
			(end 0 3.81)
			(stroke
				(width 0.1)
				(type default)
			)
			(layer "F.Fab")
		)
		(fp_line
			(start 2.54 3.81)
			(end 2.54 -1.27)
			(stroke
				(width 0.1)
				(type default)
			)
			(layer "F.Fab")
		)
		(fp_line
			(start 0 3.81)
			(end 2.54 3.81)
			(stroke
				(width 0.1)
				(type default)
			)
			(layer "F.Fab")
		)
		(fp_poly
			(pts
				(xy -0.761746 0) (xy -2.285746 -0.762) (xy -2.285746 0.762)
			)
			(stroke
				(width 0)
				(type default)
			)
			(fill yes)
			(layer "F.Fab")
		)
		(pad "1" thru_hole circle
			(at 0 0 90)
			(size 1.0033 1.0033)
			(drill 0.249936)
			(layers "*.Cu" "*.Mask")
			(remove_unused_layers no)
			(net "TDR_DIFF_85_IN1_DN")
			(clearance 0.10795)
			(thermal_gap 0.10795)
			(padstack
				(mode front_inner_back)
				(layer "Inner"
					(shape circle)
					(size 0.8001 0.8001)
					(clearance 0.1524)
				)
				(layer "B.Cu"
					(shape circle)
					(size 1.0033 1.0033)
					(clearance 0.10795)
				)
			)
		)
		(pad "2" thru_hole circle
			(at 2.54 0 90)
			(size 1.9939 1.9939)
			(drill 0.249936)
			(layers "*.Cu" "*.Mask")
			(remove_unused_layers no)
			(net "T1_GND")
			(clearance 0.10795)
			(thermal_gap 0.10795)
			(padstack
				(mode front_inner_back)
				(layer "Inner"
					(shape circle)
					(size 0.8001 0.8001)
					(clearance 0.1524)
				)
				(layer "B.Cu"
					(shape circle)
					(size 1.9939 1.9939)
					(clearance 0.10795)
				)
			)
		)
		(pad "3" thru_hole circle
			(at 2.54 2.54 90)
			(size 1.9939 1.9939)
			(drill 0.249936)
			(layers "*.Cu" "*.Mask")
			(remove_unused_layers no)
			(net "T1_GND")
			(clearance 0.10795)
			(thermal_gap 0.10795)
			(padstack
				(mode front_inner_back)
				(layer "Inner"
					(shape circle)
					(size 0.8001 0.8001)
					(clearance 0.1524)
				)
				(layer "B.Cu"
					(shape circle)
					(size 1.9939 1.9939)
					(clearance 0.10795)
				)
			)
		)
		(pad "4" thru_hole circle
			(at 0 2.54 90)
			(size 1.0033 1.0033)
			(drill 0.249936)
			(layers "*.Cu" "*.Mask")
			(remove_unused_layers no)
			(net "TDR_DIFF_85_IN1_DP")
			(clearance 0.10795)
			(thermal_gap 0.10795)
			(padstack
				(mode front_inner_back)
				(layer "Inner"
					(shape circle)
					(size 0.8001 0.8001)
					(clearance 0.1524)
				)
				(layer "B.Cu"
					(shape circle)
					(size 1.0033 1.0033)
					(clearance 0.10795)
				)
			)
		)
	)
	(footprint ""
		(layer "F.Cu")
		(at 365.62792 -395.333474)
		(property "Reference" "R616"
			(at 0 0 0)
			(layer "F.SilkS")
			(hide yes)
			(effects
				(font
					(size 1.27 1.27)
				)
			)
		)
		(property "Value" ""
			(at 0 0 0)
			(layer "F.Fab")
			(effects
				(font
					(size 1.27 1.27)
				)
			)
		)
		(duplicate_pad_numbers_are_jumpers no)
		(fp_line
			(start -0.32512 -0.175006)
			(end 0.32512 -0.175006)
			(stroke
				(width 0.1)
				(type default)
			)
			(layer "F.Fab")
		)
		(fp_line
			(start -0.32512 0.175006)
			(end -0.32512 -0.175006)
			(stroke
				(width 0.1)
				(type default)
			)
			(layer "F.Fab")
		)
		(fp_line
			(start 0.32512 -0.175006)
			(end 0.32512 0.175006)
			(stroke
				(width 0.1)
				(type default)
			)
			(layer "F.Fab")
		)
		(fp_line
			(start 0.32512 0.175006)
			(end -0.32512 0.175006)
			(stroke
				(width 0.1)
				(type default)
			)
			(layer "F.Fab")
		)
		(pad "1" smd rect
			(at -0.2667 0)
			(size 0.3048 0.381)
			(layers "F.Cu" "F.Mask" "F.Paste")
			(net "CLK_100M_RETIMER_CPU0_P3_R_DN")
		)
		(pad "2" smd rect
			(at 0.2667 0 180)
			(size 0.3048 0.381)
			(layers "F.Cu" "F.Mask" "F.Paste")
			(net "CLK_100M_RETIMER_CPU0_P3_DN")
		)
	)
	(footprint ""
		(layer "F.Cu")
		(at 289.17392 -399.553684 -90)
		(property "Reference" "R1044"
			(at 0 0 270)
			(layer "F.SilkS")
			(hide yes)
			(effects
				(font
					(size 1.27 1.27)
				)
			)
		)
		(property "Value" ""
			(at 0 0 270)
			(layer "F.Fab")
			(effects
				(font
					(size 1.27 1.27)
				)
			)
		)
		(duplicate_pad_numbers_are_jumpers no)
		(fp_line
			(start -0.32512 0.175006)
			(end -0.32512 -0.175006)
			(stroke
				(width 0.1)
				(type default)
			)
			(layer "F.Fab")
		)
		(fp_line
			(start 0.32512 0.175006)
			(end -0.32512 0.175006)
			(stroke
				(width 0.1)
				(type default)
			)
			(layer "F.Fab")
		)
		(fp_line
			(start -0.32512 -0.175006)
			(end 0.32512 -0.175006)
			(stroke
				(width 0.1)
				(type default)
			)
			(layer "F.Fab")
		)
		(fp_line
			(start 0.32512 -0.175006)
			(end 0.32512 0.175006)
			(stroke
				(width 0.1)
				(type default)
			)
			(layer "F.Fab")
		)
		(pad "1" smd rect
			(at -0.2667 0 270)
			(size 0.3048 0.381)
			(layers "F.Cu" "F.Mask" "F.Paste")
			(net "U15_E2")
		)
		(pad "2" smd rect
			(at 0.2667 0 90)
			(size 0.3048 0.381)
			(layers "F.Cu" "F.Mask" "F.Paste")
			(net "GND")
		)
	)
)
